FILE_TYPE = CONNECTIVITY;
{Allegro Design Entry HDL 17.4-2019 S026 (4007227) 1/17/2022}
"PAGE_NUMBER" = 426;
0"NC";
1"P5E_CPU0_P3_TX_C_DN<7:0>";
2"P5E_CPU0_P3_TX_C_DP<7:0>";
3"P5E_CPU0_P3_TX_C_DN<15:8>";
4"P5E_CPU0_P3_TX_C_DP<15:8>";
5"P5E_CPU0_P3_TX_C_DN<6>";
6"P5E_CPU0_P3_TX_C_DP<6>";
7"P5E_CPU0_P3_TX_C_DP<4>";
8"P5E_CPU0_P3_TX_C_DN<4>";
9"P5E_CPU0_P3_TX_C_DP<9>";
10"P5E_CPU0_P3_TX_C_DP<10>";
11"P5E_CPU0_P3_TX_C_DP<11>";
12"P5E_CPU0_P3_TX_C_DP<13>";
13"P5E_CPU0_P3_TX_C_DP<14>";
14"P5E_CPU0_P3_TX_C_DP<15>";
15"P5E_CPU0_P3_TX_C_DN<14>";
16"P5E_CPU0_P3_TX_C_DP<12>";
17"P5E_CPU0_P3_TX_C_DP<8>";
18"P5E_CPU0_P3_TX_C_DN<9>";
19"P5E_CPU0_P3_TX_C_DN<10>";
20"P5E_CPU0_P3_TX_C_DN<11>";
21"P5E_CPU0_P3_TX_C_DN<12>";
22"P5E_CPU0_P3_TX_C_DN<13>";
23"P5E_CPU0_P3_TX_C_DN<15>";
24"P5E_CPU0_P3_TX_C_DN<8>";
25"P5E_CPU0_P3_TX_C_DN<0>";
26"P5E_CPU0_P3_TX_C_DN<1>";
27"P5E_CPU0_P3_TX_C_DP<1>";
28"P5E_CPU0_P3_TX_C_DP<2>";
29"P5E_CPU0_P3_TX_C_DN<2>";
30"P5E_CPU0_P3_TX_C_DP<3>";
31"P5E_CPU0_P3_TX_C_DN<3>";
32"P5E_CPU0_P3_TX_C_DP<5>";
33"P5E_CPU0_P3_TX_C_DN<5>";
34"P5E_CPU0_P3_TX_C_DP<7>";
35"P5E_CPU0_P3_TX_C_DP<0>";
36"P5E_CPU0_P3_TX_C_DN<7>";
%"PT5161LRS"
"8","(-7825,4175)","0","pure_quanta","I1";
;
LOCATION"U6013"
$SEC"8"
CDS_SEC"8"
MATERIAL"IC"
VALUE"PT5161LRS"
PART_TYPE"SMLF"
NEEDS_NO_SIZE"TRUE"
CDS_LMAN_SYM_OUTLINE"-350,1450,300,-1400"
CDS_LIB"pure_quanta"
PART_NUMBER"AJ051610U03";
"B_PERN7"
$PN"CD35"17;
"B_PERP7"
$PN"CB34"24;
"B_PERN6"
$PN"BU35"9;
"B_PERP6"
$PN"BR34"18;
"B_PERN5"
$PN"BK35"10;
"B_PERP5"
$PN"BH34"19;
"B_PERN4"
$PN"BC35"11;
"B_PERP4"
$PN"BA34"20;
"B_PERN3"
$PN"AT35"16;
"B_PERP3"
$PN"AP34"21;
"B_PERN2"
$PN"AJ35"12;
"B_PERP2"
$PN"AG34"22;
"B_PERN1"
$PN"AB35"15;
"B_PERP1"
$PN"Y34"13;
"B_PERN0"
$PN"R35"14;
"B_PERP0"
$PN"N34"23;
%"TAP"
"1","(-6800,4375)","0","standard","I10";
;
CDS_LIB"standard"
BODY_TYPE"PLUMBING"
HDL_TAP"TRUE";
"B \NAC \NWC"3;
"S \NAC"
BN"12"21;
%"TAP"
"1","(-6600,4275)","0","standard","I11";
;
CDS_LIB"standard"
BODY_TYPE"PLUMBING"
HDL_TAP"TRUE";
"B \NAC \NWC"4;
"S \NAC"
BN"12"16;
%"TAP"
"1","(-6800,4725)","0","standard","I12";
;
CDS_LIB"standard"
BODY_TYPE"PLUMBING"
HDL_TAP"TRUE";
"B \NAC \NWC"3;
"S \NAC"
BN"13"22;
%"TAP"
"1","(-6600,4625)","0","standard","I13";
;
CDS_LIB"standard"
BODY_TYPE"PLUMBING"
HDL_TAP"TRUE";
"B \NAC \NWC"4;
"S \NAC"
BN"13"12;
%"TAP"
"1","(-6800,4975)","0","standard","I14";
;
CDS_LIB"standard"
BODY_TYPE"PLUMBING"
HDL_TAP"TRUE";
"B \NAC \NWC"3;
"S \NAC"
BN"14"15;
%"TAP"
"1","(-6800,5425)","0","standard","I15";
;
CDS_LIB"standard"
BODY_TYPE"PLUMBING"
HDL_TAP"TRUE";
"B \NAC \NWC"3;
"S \NAC"
BN"15"23;
%"TAP"
"1","(-6600,5075)","0","standard","I16";
;
CDS_LIB"standard"
BODY_TYPE"PLUMBING"
HDL_TAP"TRUE";
"B \NAC \NWC"4;
"S \NAC"
BN"14"13;
%"TAP"
"1","(-6600,5325)","0","standard","I17";
;
CDS_LIB"standard"
BODY_TYPE"PLUMBING"
HDL_TAP"TRUE";
"B \NAC \NWC"4;
"S \NAC"
BN"15"14;
%"TAP"
"1","(-6600,2875)","0","standard","I2";
;
CDS_LIB"standard"
BODY_TYPE"PLUMBING"
HDL_TAP"TRUE";
"B \NAC \NWC"4;
"S \NAC"
BN"8"17;
%"TAP"
"1","(-2175,3175)","0","standard","I20";
;
CDS_LIB"standard"
BODY_TYPE"PLUMBING"
HDL_TAP"TRUE";
"B \NAC \NWC"1;
"S \NAC"
BN"1"26;
%"TAP"
"1","(-1975,3275)","0","standard","I21";
;
CDS_LIB"standard"
BODY_TYPE"PLUMBING"
HDL_TAP"TRUE";
"B \NAC \NWC"2;
"S \NAC"
BN"1"27;
%"TAP"
"1","(-2175,3625)","0","standard","I22";
;
CDS_LIB"standard"
BODY_TYPE"PLUMBING"
HDL_TAP"TRUE";
"B \NAC \NWC"1;
"S \NAC"
BN"2"29;
%"TAP"
"1","(-1975,3525)","0","standard","I23";
;
CDS_LIB"standard"
BODY_TYPE"PLUMBING"
HDL_TAP"TRUE";
"B \NAC \NWC"2;
"S \NAC"
BN"2"28;
%"TAP"
"1","(-1975,3875)","0","standard","I24";
;
CDS_LIB"standard"
BODY_TYPE"PLUMBING"
HDL_TAP"TRUE";
"B \NAC \NWC"2;
"S \NAC"
BN"3"30;
%"TAP"
"1","(-2175,3975)","0","standard","I25";
;
CDS_LIB"standard"
BODY_TYPE"PLUMBING"
HDL_TAP"TRUE";
"B \NAC \NWC"1;
"S \NAC"
BN"3"31;
%"TAP"
"1","(-2175,4325)","0","standard","I26";
;
CDS_LIB"standard"
BODY_TYPE"PLUMBING"
HDL_TAP"TRUE";
"B \NAC \NWC"1;
"S \NAC"
BN"4"8;
%"TAP"
"1","(-1975,4225)","0","standard","I27";
;
CDS_LIB"standard"
BODY_TYPE"PLUMBING"
HDL_TAP"TRUE";
"B \NAC \NWC"2;
"S \NAC"
BN"4"7;
%"TAP"
"1","(-2175,4675)","0","standard","I28";
;
CDS_LIB"standard"
BODY_TYPE"PLUMBING"
HDL_TAP"TRUE";
"B \NAC \NWC"1;
"S \NAC"
BN"5"33;
%"TAP"
"1","(-1975,4575)","0","standard","I29";
;
CDS_LIB"standard"
BODY_TYPE"PLUMBING"
HDL_TAP"TRUE";
"B \NAC \NWC"2;
"S \NAC"
BN"5"32;
%"TAP"
"1","(-6800,2975)","0","standard","I3";
;
CDS_LIB"standard"
BODY_TYPE"PLUMBING"
HDL_TAP"TRUE";
"B \NAC \NWC"3;
"S \NAC"
BN"8"24;
%"TAP"
"1","(-1975,4925)","0","standard","I30";
;
CDS_LIB"standard"
BODY_TYPE"PLUMBING"
HDL_TAP"TRUE";
"B \NAC \NWC"2;
"S \NAC"
BN"6"6;
%"TAP"
"1","(-2175,5025)","0","standard","I31";
;
CDS_LIB"standard"
BODY_TYPE"PLUMBING"
HDL_TAP"TRUE";
"B \NAC \NWC"1;
"S \NAC"
BN"6"5;
%"TAP"
"1","(-2175,5375)","0","standard","I32";
;
CDS_LIB"standard"
BODY_TYPE"PLUMBING"
HDL_TAP"TRUE";
"B \NAC \NWC"1;
"S \NAC"
BN"7"36;
%"TAP"
"1","(-1975,5275)","0","standard","I33";
;
CDS_LIB"standard"
BODY_TYPE"PLUMBING"
HDL_TAP"TRUE";
"B \NAC \NWC"2;
"S \NAC"
BN"7"34;
%"TAP"
"1","(-1975,2825)","0","standard","I36";
;
CDS_LIB"standard"
BODY_TYPE"PLUMBING"
HDL_TAP"TRUE";
"B \NAC \NWC"2;
"S \NAC"
BN"0"35;
%"TAP"
"1","(-2175,2925)","0","standard","I37";
;
CDS_LIB"standard"
BODY_TYPE"PLUMBING"
HDL_TAP"TRUE";
"B \NAC \NWC"1;
"S \NAC"
BN"0"25;
%"PT5161LRS"
"9","(-3200,4125)","0","pure_quanta","I38";
;
LOCATION"U6013"
$SEC"9"
CDS_SEC"9"
MATERIAL"IC"
VALUE"PT5161LRS"
PART_TYPE"SMLF"
CDS_LIB"pure_quanta"
CDS_LMAN_SYM_OUTLINE"-350,1450,300,-1400"
NEEDS_NO_SIZE"TRUE"
PART_NUMBER"AJ051610U03";
"B_PERN15"
$PN"EY35"35;
"B_PERP15"
$PN"EV34"25;
"B_PERN14"
$PN"EN35"26;
"B_PERP14"
$PN"EL34"27;
"B_PERN13"
$PN"EF35"28;
"B_PERP13"
$PN"ED34"29;
"B_PERN12"
$PN"DW35"30;
"B_PERP12"
$PN"DU34"31;
"B_PERN11"
$PN"DM35"7;
"B_PERP11"
$PN"DK34"8;
"B_PERN10"
$PN"DE35"32;
"B_PERP10"
$PN"DC34"33;
"B_PERN9"
$PN"CV35"6;
"B_PERP9"
$PN"CT34"5;
"B_PERN8"
$PN"CL35"34;
"B_PERP8"
$PN"CJ34"36;
%"TAP"
"1","(-6800,3325)","0","standard","I4";
;
CDS_LIB"standard"
BODY_TYPE"PLUMBING"
HDL_TAP"TRUE";
"B \NAC \NWC"3;
"S \NAC"
BN"9"18;
%"TAP"
"1","(-6600,3225)","0","standard","I5";
;
CDS_LIB"standard"
BODY_TYPE"PLUMBING"
HDL_TAP"TRUE";
"B \NAC \NWC"4;
"S \NAC"
BN"9"9;
%"TAP"
"1","(-6800,3675)","0","standard","I6";
;
CDS_LIB"standard"
BODY_TYPE"PLUMBING"
HDL_TAP"TRUE";
"B \NAC \NWC"3;
"S \NAC"
BN"10"19;
%"TAP"
"1","(-6600,3575)","0","standard","I7";
;
CDS_LIB"standard"
BODY_TYPE"PLUMBING"
HDL_TAP"TRUE";
"B \NAC \NWC"4;
"S \NAC"
BN"10"10;
%"TAP"
"1","(-6600,3925)","0","standard","I8";
;
CDS_LIB"standard"
BODY_TYPE"PLUMBING"
HDL_TAP"TRUE";
"B \NAC \NWC"4;
"S \NAC"
BN"11"11;
%"TAP"
"1","(-6800,4025)","0","standard","I9";
;
CDS_LIB"standard"
BODY_TYPE"PLUMBING"
HDL_TAP"TRUE";
"B \NAC \NWC"3;
"S \NAC"
BN"11"20;
END.
